(kicad_pcb
	(version 20260206)
	(generator "pcbnew")
	(generator_version "10.0")
	(general
		(thickness 1.6)
		(legacy_teardrops no)
	)
	(paper "A4")
	(title_block
		(title "timecard-production-celestica-r4006 — R4006-B0001-02_R01.brd")
		(comment 1 "Time Appliance Project (Time Card) / footprints 538-541 of 1113")
	)
	(layers
		(0 "F.Cu" signal "TOP")
		(4 "In1.Cu" signal "L02_GND1")
		(6 "In2.Cu" signal "L03_SIG1")
		(8 "In3.Cu" signal "L04_GND2")
		(10 "In4.Cu" signal "L05_VCC1")
		(12 "In5.Cu" signal "L06_VCC2")
		(14 "In6.Cu" signal "L07_GND3")
		(16 "In7.Cu" signal "L08_SIG2")
		(18 "In8.Cu" signal "L09_GND4")
		(2 "B.Cu" signal "BOTTOM")
		(9 "F.Adhes" user "F.Adhesive")
		(11 "B.Adhes" user "B.Adhesive")
		(13 "F.Paste" user "Package Geometry/Pastemask Top")
		(15 "B.Paste" user "Package Geometry/Pastemask Bottom")
		(5 "F.SilkS" user "Ref Des/Silkscreen Top")
		(7 "B.SilkS" user "Ref Des/Silkscreen Bottom")
		(1 "F.Mask" user "Board Geometry/Soldermask Top")
		(3 "B.Mask" user "Board Geometry/Soldermask Bottom")
		(17 "Dwgs.User" user "User.Drawings")
		(19 "Cmts.User" user "User.Comments")
		(21 "Eco1.User" user "User.Eco1")
		(23 "Eco2.User" user "User.Eco2")
		(25 "Edge.Cuts" user "Board Geometry/Outline")
		(27 "Margin" user)
		(31 "F.CrtYd" user "Package Geometry/Place Bound Top")
		(29 "B.CrtYd" user "Package Geometry/Place Bound Bottom")
		(35 "F.Fab" user "Ref Des/Assembly Top")
		(33 "B.Fab" user "Ref Des/Assembly Bottom")
	)
	(footprint ""
		(layer "F.Cu")
		(at 28.5242 -85.0646 -90)
		(property "Reference" "U18"
			(at -1.4224 -8.09117 90)
			(unlocked yes)
			(layer "F.SilkS")
			(effects
				(font
					(size 0.7874 0.5842)
					(thickness 0.1524)
				)
			)
		)
		(property "Value" ""
			(at 0 0 270)
			(layer "F.Fab")
			(effects
				(font
					(size 1.27 1.27)
				)
			)
		)
		(property "Device Type" "FT4232HL_REEL_QFP64-G223-10282A"
			(at -0.0127 7.86257 270)
			(unlocked yes)
			(layer "F.Fab")
			(hide yes)
			(effects
				(font
					(size 0.381 0.254)
					(thickness 0.000001)
				)
			)
		)
		(property "User Part Number" "PARTNUM*"
			(at 0.17018 8.41375 270)
			(unlocked yes)
			(layer "Cmts.User")
			(hide yes)
			(effects
				(font
					(size 0.381 0.254)
					(thickness 0.000001)
				)
			)
		)
		(duplicate_pad_numbers_are_jumpers no)
		(fp_line
			(start -6.8834 6.8834)
			(end -6.8834 -6.8834)
			(stroke
				(width 0.1)
				(type default)
			)
			(layer "F.SilkS")
		)
		(fp_line
			(start 6.8834 6.8834)
			(end -6.8834 6.8834)
			(stroke
				(width 0.1)
				(type default)
			)
			(layer "F.SilkS")
		)
		(fp_line
			(start -6.8834 -6.8834)
			(end 6.8834 -6.8834)
			(stroke
				(width 0.1)
				(type default)
			)
			(layer "F.SilkS")
		)
		(fp_line
			(start 6.8834 -6.8834)
			(end 6.8834 6.8834)
			(stroke
				(width 0.1)
				(type default)
			)
			(layer "F.SilkS")
		)
		(fp_poly
			(pts
				(arc
					(start -7.645908 -4.577588)
					(mid -7.645908 -3.561588)
					(end -7.645908 -4.577588)
				)
			)
			(stroke
				(width 0)
				(type default)
			)
			(fill yes)
			(layer "F.SilkS")
		)
		(fp_rect
			(start -7.1374 7.1374)
			(end 7.1374 -7.1374)
			(stroke
				(width 0)
				(type default)
			)
			(fill no)
			(layer "F.CrtYd")
		)
		(fp_line
			(start -5.0038 5.0038)
			(end 5.0038 5.0038)
			(stroke
				(width 0.1)
				(type default)
			)
			(layer "F.Fab")
		)
		(fp_line
			(start 5.0038 5.0038)
			(end 5.0038 -5.0038)
			(stroke
				(width 0.1)
				(type default)
			)
			(layer "F.Fab")
		)
		(fp_line
			(start -5.0038 -5.0038)
			(end -5.0038 5.0038)
			(stroke
				(width 0.1)
				(type default)
			)
			(layer "F.Fab")
		)
		(fp_line
			(start 5.0038 -5.0038)
			(end -5.0038 -5.0038)
			(stroke
				(width 0.1)
				(type default)
			)
			(layer "F.Fab")
		)
		(fp_poly
			(pts
				(arc
					(start -7.66318 -4.57708)
					(mid -7.66318 -3.56108)
					(end -7.66318 -4.57708)
				)
			)
			(stroke
				(width 0)
				(type default)
			)
			(fill yes)
			(layer "F.Fab")
		)
		(fp_text user "32"
			(at 3.94335 7.4422 0)
			(unlocked yes)
			(layer "F.SilkS")
			(effects
				(font
					(size 0.635 0.4064)
					(thickness 0.1524)
				)
			)
		)
		(fp_text user "17"
			(at -3.7084 7.33425 90)
			(unlocked yes)
			(layer "F.SilkS")
			(effects
				(font
					(size 0.635 0.4064)
					(thickness 0.1524)
				)
			)
		)
		(fp_text user "33"
			(at 7.49935 4.0132 0)
			(unlocked yes)
			(layer "F.SilkS")
			(effects
				(font
					(size 0.635 0.4064)
					(thickness 0.1524)
				)
			)
		)
		(fp_text user "16"
			(at -7.35965 3.7592 0)
			(unlocked yes)
			(layer "F.SilkS")
			(effects
				(font
					(size 0.635 0.4064)
					(thickness 0.1524)
				)
			)
		)
		(fp_text user "48"
			(at 7.62635 -4.1148 0)
			(unlocked yes)
			(layer "F.SilkS")
			(effects
				(font
					(size 0.635 0.4064)
					(thickness 0.1524)
				)
			)
		)
		(fp_text user "49"
			(at 4.5466 -7.32155 90)
			(unlocked yes)
			(layer "F.SilkS")
			(effects
				(font
					(size 0.635 0.4064)
					(thickness 0.1524)
				)
			)
		)
		(fp_text user "64"
			(at -4.48945 -8.0518 0)
			(unlocked yes)
			(layer "F.SilkS")
			(effects
				(font
					(size 0.635 0.4064)
					(thickness 0.1524)
				)
			)
		)
		(fp_text user "17"
			(at -3.975354 7.37743 90)
			(unlocked yes)
			(layer "F.Fab")
			(effects
				(font
					(size 0.7874 0.5842)
					(thickness 0.1524)
				)
			)
		)
		(fp_text user "32"
			(at 3.866134 7.371588 90)
			(unlocked yes)
			(layer "F.Fab")
			(effects
				(font
					(size 0.7874 0.5842)
					(thickness 0.1524)
				)
			)
		)
		(fp_text user "16"
			(at -7.2644 4.35483 90)
			(unlocked yes)
			(layer "F.Fab")
			(effects
				(font
					(size 0.7874 0.5842)
					(thickness 0.1524)
				)
			)
		)
		(fp_text user "33"
			(at 7.478268 3.852672 90)
			(unlocked yes)
			(layer "F.Fab")
			(effects
				(font
					(size 0.7874 0.5842)
					(thickness 0.1524)
				)
			)
		)
		(fp_text user "48"
			(at 7.48411 -3.795776 90)
			(unlocked yes)
			(layer "F.Fab")
			(effects
				(font
					(size 0.7874 0.5842)
					(thickness 0.1524)
				)
			)
		)
		(fp_text user "49"
			(at 3.931666 -7.32917 90)
			(unlocked yes)
			(layer "F.Fab")
			(effects
				(font
					(size 0.7874 0.5842)
					(thickness 0.1524)
				)
			)
		)
		(fp_text user "64"
			(at -3.946906 -7.33933 90)
			(unlocked yes)
			(layer "F.Fab")
			(effects
				(font
					(size 0.7874 0.5842)
					(thickness 0.1524)
				)
			)
		)
		(pad "1" smd rect
			(at -5.8166 -3.750056)
			(size 0.3048 1.6256)
			(layers "F.Cu" "F.Mask" "F.Paste")
			(net "SG")
		)
		(pad "2" smd rect
			(at -5.8166 -3.24993)
			(size 0.3048 1.6256)
			(layers "F.Cu" "F.Mask" "F.Paste")
			(net "UNNAMED_524_CAPACITOR_I7_2")
		)
		(pad "3" smd rect
			(at -5.8166 -2.750058)
			(size 0.3048 1.6256)
			(layers "F.Cu" "F.Mask" "F.Paste")
			(net "UNNAMED_524_CAPACITOR_I10_2")
		)
		(pad "4" smd rect
			(at -5.8166 -2.249932)
			(size 0.3048 1.6256)
			(layers "F.Cu" "F.Mask" "F.Paste")
			(net "XP3R3V_VPHY")
		)
		(pad "5" smd rect
			(at -5.8166 -1.75006)
			(size 0.3048 1.6256)
			(layers "F.Cu" "F.Mask" "F.Paste")
			(net "SG")
		)
		(pad "6" smd rect
			(at -5.8166 -1.249934)
			(size 0.3048 1.6256)
			(layers "F.Cu" "F.Mask" "F.Paste")
			(net "UNNAMED_524_FT4232HLREELQFP64_6")
		)
		(pad "7" smd rect
			(at -5.8166 -0.750062)
			(size 0.3048 1.6256)
			(layers "F.Cu" "F.Mask" "F.Paste")
			(net "R_FT_USB_DM")
		)
		(pad "8" smd rect
			(at -5.8166 -0.249936)
			(size 0.3048 1.6256)
			(layers "F.Cu" "F.Mask" "F.Paste")
			(net "R_FT_USB_DP")
		)
		(pad "9" smd rect
			(at -5.8166 0.249936)
			(size 0.3048 1.6256)
			(layers "F.Cu" "F.Mask" "F.Paste")
			(net "XP3R3V_VPLL")
		)
		(pad "10" smd rect
			(at -5.8166 0.750062)
			(size 0.3048 1.6256)
			(layers "F.Cu" "F.Mask" "F.Paste")
			(net "SG")
		)
		(pad "11" smd rect
			(at -5.8166 1.249934)
			(size 0.3048 1.6256)
			(layers "F.Cu" "F.Mask" "F.Paste")
			(net "SG")
		)
		(pad "12" smd rect
			(at -5.8166 1.75006)
			(size 0.3048 1.6256)
			(layers "F.Cu" "F.Mask" "F.Paste")
			(net "FT4232_VREGOUT")
		)
		(pad "13" smd rect
			(at -5.8166 2.249932)
			(size 0.3048 1.6256)
			(layers "F.Cu" "F.Mask" "F.Paste")
			(net "SG")
		)
		(pad "14" smd rect
			(at -5.8166 2.750058)
			(size 0.3048 1.6256)
			(layers "F.Cu" "F.Mask" "F.Paste")
			(net "UNNAMED_524_FT4232HLREELQFP64_7")
		)
		(pad "15" smd rect
			(at -5.8166 3.24993)
			(size 0.3048 1.6256)
			(layers "F.Cu" "F.Mask" "F.Paste")
			(net "SG")
		)
		(pad "16" smd rect
			(at -5.8166 3.750056)
			(size 0.3048 1.6256)
			(layers "F.Cu" "F.Mask" "F.Paste")
			(net "R_FT4232_TCK")
		)
		(pad "17" smd rect
			(at -3.750056 5.8166 90)
			(size 0.3048 1.6256)
			(layers "F.Cu" "F.Mask" "F.Paste")
			(net "R_FT4232_TDI")
		)
		(pad "18" smd rect
			(at -3.24993 5.8166 90)
			(size 0.3048 1.6256)
			(layers "F.Cu" "F.Mask" "F.Paste")
			(net "R_FT4232_TDO")
		)
		(pad "19" smd rect
			(at -2.750058 5.8166 90)
			(size 0.3048 1.6256)
			(layers "F.Cu" "F.Mask" "F.Paste")
			(net "R_FT4232_TMS")
		)
		(pad "20" smd rect
			(at -2.249932 5.8166 90)
			(size 0.3048 1.6256)
			(layers "F.Cu" "F.Mask" "F.Paste")
			(net "XP3R3V_FT4232")
		)
		(pad "21" smd rect
			(at -1.75006 5.8166 90)
			(size 0.3048 1.6256)
			(layers "F.Cu" "F.Mask" "F.Paste")
			(net "FT4232_MUX1_SEL")
		)
		(pad "22" smd rect
			(at -1.249934 5.8166 90)
			(size 0.3048 1.6256)
			(layers "F.Cu" "F.Mask" "F.Paste")
			(net "FT4232_MUX2_SEL")
		)
		(pad "23" smd rect
			(at -0.750062 5.8166 90)
			(size 0.3048 1.6256)
			(layers "F.Cu" "F.Mask" "F.Paste")
			(net "FT4232_MUX3_SEL")
		)
		(pad "24" smd rect
			(at -0.249936 5.8166 90)
			(size 0.3048 1.6256)
			(layers "F.Cu" "F.Mask" "F.Paste")
			(net "UNNAMED_524_FT4232HLREELQFP64_I")
		)
		(pad "25" smd rect
			(at 0.249936 5.8166 90)
			(size 0.3048 1.6256)
			(layers "F.Cu" "F.Mask" "F.Paste")
			(net "SG")
		)
		(pad "26" smd rect
			(at 0.750062 5.8166 90)
			(size 0.3048 1.6256)
			(layers "F.Cu" "F.Mask" "F.Paste")
			(net "R_FT4232_I2C_SCL")
		)
		(pad "27" smd rect
			(at 1.249934 5.8166 90)
			(size 0.3048 1.6256)
			(layers "F.Cu" "F.Mask" "F.Paste")
			(net "R_FT4232_I2C_SDA_OUT")
		)
		(pad "28" smd rect
			(at 1.75006 5.8166 90)
			(size 0.3048 1.6256)
			(layers "F.Cu" "F.Mask" "F.Paste")
			(net "R_FT4232_I2C_SDA_IN")
		)
		(pad "29" smd rect
			(at 2.249932 5.8166 90)
			(size 0.3048 1.6256)
			(layers "F.Cu" "F.Mask" "F.Paste")
			(net "UNNAMED_524_FT4232HLREELQFP64_1")
		)
		(pad "30" smd rect
			(at 2.750058 5.8166 90)
			(size 0.3048 1.6256)
			(layers "F.Cu" "F.Mask" "F.Paste")
			(net "UNNAMED_524_FT4232HLREELQFP64_2")
		)
		(pad "31" smd rect
			(at 3.24993 5.8166 90)
			(size 0.3048 1.6256)
			(layers "F.Cu" "F.Mask" "F.Paste")
			(net "XP3R3V_FT4232")
		)
		(pad "32" smd rect
			(at 3.750056 5.8166 90)
			(size 0.3048 1.6256)
			(layers "F.Cu" "F.Mask" "F.Paste")
			(net "UNNAMED_524_FT4232HLREELQFP64_3")
		)
		(pad "33" smd rect
			(at 5.8166 3.750056)
			(size 0.3048 1.6256)
			(layers "F.Cu" "F.Mask" "F.Paste")
			(net "UNNAMED_524_FT4232HLREELQFP64_4")
		)
		(pad "34" smd rect
			(at 5.8166 3.24993)
			(size 0.3048 1.6256)
			(layers "F.Cu" "F.Mask" "F.Paste")
			(net "UNNAMED_524_FT4232HLREELQFP64_5")
		)
		(pad "35" smd rect
			(at 5.8166 2.750058)
			(size 0.3048 1.6256)
			(layers "F.Cu" "F.Mask" "F.Paste")
			(net "SG")
		)
		(pad "36" smd rect
			(at 5.8166 2.249932)
			(size 0.3048 1.6256)
			(layers "F.Cu" "F.Mask" "F.Paste")
			(net "Net_789")
		)
		(pad "37" smd rect
			(at 5.8166 1.75006)
			(size 0.3048 1.6256)
			(layers "F.Cu" "F.Mask" "F.Paste")
			(net "FT4232_VREGOUT")
		)
		(pad "38" smd rect
			(at 5.8166 1.249934)
			(size 0.3048 1.6256)
			(layers "F.Cu" "F.Mask" "F.Paste")
			(net "R_FT4232_CHC_TX")
		)
		(pad "39" smd rect
			(at 5.8166 0.750062)
			(size 0.3048 1.6256)
			(layers "F.Cu" "F.Mask" "F.Paste")
			(net "R_FT4232_CHC_RX")
		)
		(pad "40" smd rect
			(at 5.8166 0.249936)
			(size 0.3048 1.6256)
			(layers "F.Cu" "F.Mask" "F.Paste")
			(net "Net_802")
		)
		(pad "41" smd rect
			(at 5.8166 -0.249936)
			(size 0.3048 1.6256)
			(layers "F.Cu" "F.Mask" "F.Paste")
			(net "Net_801")
		)
		(pad "42" smd rect
			(at 5.8166 -0.750062)
			(size 0.3048 1.6256)
			(layers "F.Cu" "F.Mask" "F.Paste")
			(net "XP3R3V_FT4232")
		)
		(pad "43" smd rect
			(at 5.8166 -1.249934)
			(size 0.3048 1.6256)
			(layers "F.Cu" "F.Mask" "F.Paste")
			(net "Net_800")
		)
		(pad "44" smd rect
			(at 5.8166 -1.75006)
			(size 0.3048 1.6256)
			(layers "F.Cu" "F.Mask" "F.Paste")
			(net "Net_799")
		)
		(pad "45" smd rect
			(at 5.8166 -2.249932)
			(size 0.3048 1.6256)
			(layers "F.Cu" "F.Mask" "F.Paste")
			(net "Net_798")
		)
		(pad "46" smd rect
			(at 5.8166 -2.750058)
			(size 0.3048 1.6256)
			(layers "F.Cu" "F.Mask" "F.Paste")
			(net "Net_797")
		)
		(pad "47" smd rect
			(at 5.8166 -3.24993)
			(size 0.3048 1.6256)
			(layers "F.Cu" "F.Mask" "F.Paste")
			(net "SG")
		)
		(pad "48" smd rect
			(at 5.8166 -3.750056)
			(size 0.3048 1.6256)
			(layers "F.Cu" "F.Mask" "F.Paste")
			(net "R_FT4232_CHD_TX")
		)
		(pad "49" smd rect
			(at 3.750056 -5.8166 90)
			(size 0.3048 1.6256)
			(layers "F.Cu" "F.Mask" "F.Paste")
			(net "FT4232_VREGOUT")
		)
		(pad "50" smd rect
			(at 3.24993 -5.8166 90)
			(size 0.3048 1.6256)
			(layers "F.Cu" "F.Mask" "F.Paste")
			(net "XP3R3V_FT4232")
		)
		(pad "51" smd rect
			(at 2.750058 -5.8166 90)
			(size 0.3048 1.6256)
			(layers "F.Cu" "F.Mask" "F.Paste")
			(net "SG")
		)
		(pad "52" smd rect
			(at 2.249932 -5.8166 90)
			(size 0.3048 1.6256)
			(layers "F.Cu" "F.Mask" "F.Paste")
			(net "R_FT4232_CHD_RX")
		)
		(pad "53" smd rect
			(at 1.75006 -5.8166 90)
			(size 0.3048 1.6256)
			(layers "F.Cu" "F.Mask" "F.Paste")
			(net "Net_796")
		)
		(pad "54" smd rect
			(at 1.249934 -5.8166 90)
			(size 0.3048 1.6256)
			(layers "F.Cu" "F.Mask" "F.Paste")
			(net "Net_795")
		)
		(pad "55" smd rect
			(at 0.750062 -5.8166 90)
			(size 0.3048 1.6256)
			(layers "F.Cu" "F.Mask" "F.Paste")
			(net "Net_794")
		)
		(pad "56" smd rect
			(at 0.249936 -5.8166 90)
			(size 0.3048 1.6256)
			(layers "F.Cu" "F.Mask" "F.Paste")
			(net "XP3R3V_FT4232")
		)
		(pad "57" smd rect
			(at -0.249936 -5.8166 90)
			(size 0.3048 1.6256)
			(layers "F.Cu" "F.Mask" "F.Paste")
			(net "Net_793")
		)
		(pad "58" smd rect
			(at -0.750062 -5.8166 90)
			(size 0.3048 1.6256)
			(layers "F.Cu" "F.Mask" "F.Paste")
			(net "Net_792")
		)
		(pad "59" smd rect
			(at -1.249934 -5.8166 90)
			(size 0.3048 1.6256)
			(layers "F.Cu" "F.Mask" "F.Paste")
			(net "Net_791")
		)
		(pad "60" smd rect
			(at -1.75006 -5.8166 90)
			(size 0.3048 1.6256)
			(layers "F.Cu" "F.Mask" "F.Paste")
			(net "Net_790")
		)
		(pad "61" smd rect
			(at -2.249932 -5.8166 90)
			(size 0.3048 1.6256)
			(layers "F.Cu" "F.Mask" "F.Paste")
			(net "FTDI_EE_DAT")
		)
		(pad "62" smd rect
			(at -2.750058 -5.8166 90)
			(size 0.3048 1.6256)
			(layers "F.Cu" "F.Mask" "F.Paste")
			(net "FTDI_EE_CLK")
		)
		(pad "63" smd rect
			(at -3.24993 -5.8166 90)
			(size 0.3048 1.6256)
			(layers "F.Cu" "F.Mask" "F.Paste")
			(net "FTDI_EE_CS")
		)
		(pad "64" smd rect
			(at -3.750056 -5.8166 90)
			(size 0.3048 1.6256)
			(layers "F.Cu" "F.Mask" "F.Paste")
			(net "FT4232_VREGOUT")
		)
	)
	(footprint ""
		(layer "F.Cu")
		(at 72.661018 -67.066922)
		(property "Reference" "MAC_PIN5"
			(at 0.998982 -3.129026 0)
			(unlocked yes)
			(layer "F.SilkS")
			(effects
				(font
					(size 0.7874 0.5842)
					(thickness 0.1524)
				)
			)
		)
		(property "Value" ""
			(at 0 0 0)
			(layer "F.Fab")
			(effects
				(font
					(size 1.27 1.27)
				)
			)
		)
		(property "Device Type" "NUT-A200-00029-FB"
			(at 0 2.632964 0)
			(unlocked yes)
			(layer "F.Fab")
			(hide yes)
			(effects
				(font
					(size 0.7874 0.5842)
					(thickness 0.1524)
				)
			)
		)
		(property "User Part Number" "PARTNUM*"
			(at 0 3.826764 0)
			(unlocked yes)
			(layer "Cmts.User")
			(hide yes)
			(effects
				(font
					(size 0.7874 0.5842)
					(thickness 0.1524)
				)
			)
		)
		(duplicate_pad_numbers_are_jumpers no)
		(fp_circle
			(center 0 0)
			(end 1.524 0)
			(stroke
				(width 0.1)
				(type default)
			)
			(fill no)
			(layer "F.SilkS")
		)
		(fp_poly
			(pts
				(arc
					(start -1.260856 -0.1524)
					(mid -0.898049 -0.898049)
					(end -0.1524 -1.260856)
				)
				(arc
					(start -0.1524 -0.991616)
					(mid -0.709411 -0.709411)
					(end -0.991616 -0.1524)
				)
			)
			(stroke
				(width 0)
				(type default)
			)
			(fill yes)
			(layer "F.Paste")
		)
		(fp_poly
			(pts
				(arc
					(start -0.1524 1.260856)
					(mid -0.898049 0.898049)
					(end -1.260856 0.1524)
				)
				(arc
					(start -0.991616 0.1524)
					(mid -0.709411 0.709411)
					(end -0.1524 0.991616)
				)
			)
			(stroke
				(width 0)
				(type default)
			)
			(fill yes)
			(layer "F.Paste")
		)
		(fp_poly
			(pts
				(arc
					(start 0.1524 -1.260856)
					(mid 0.898049 -0.898049)
					(end 1.260856 -0.1524)
				)
				(arc
					(start 0.991616 -0.1524)
					(mid 0.709411 -0.709411)
					(end 0.1524 -0.991616)
				)
			)
			(stroke
				(width 0)
				(type default)
			)
			(fill yes)
			(layer "F.Paste")
		)
		(fp_poly
			(pts
				(arc
					(start 1.260856 0.1524)
					(mid 0.898049 0.898049)
					(end 0.1524 1.260856)
				)
				(arc
					(start 0.1524 0.991616)
					(mid 0.709411 0.709411)
					(end 0.991616 0.1524)
				)
			)
			(stroke
				(width 0)
				(type default)
			)
			(fill yes)
			(layer "F.Paste")
		)
		(fp_poly
			(pts
				(arc
					(start 6.35 0)
					(mid -6.35 0)
					(end 6.35 0)
				)
			)
			(stroke
				(width 0)
				(type default)
			)
			(fill no)
			(layer "B.CrtYd")
		)
		(fp_poly
			(pts
				(arc
					(start 1.778 0)
					(mid -1.778 0)
					(end 1.778 0)
				)
			)
			(stroke
				(width 0)
				(type default)
			)
			(fill no)
			(layer "F.CrtYd")
		)
		(fp_circle
			(center 0 0)
			(end 1.1684 0)
			(stroke
				(width 0.1)
				(type default)
			)
			(fill no)
			(layer "F.Fab")
		)
		(pad "1" thru_hole circle
			(at 0 0)
			(size 2.54 2.54)
			(drill 2.0066)
			(layers "*.Cu" "*.Mask")
			(remove_unused_layers no)
			(net "XP5R0V_MAC")
			(thermal_gap 0.0254)
			(padstack
				(mode front_inner_back)
				(layer "Inner"
					(shape circle)
					(size 2.54 2.54)
					(clearance 0.0254)
				)
				(layer "B.Cu"
					(shape circle)
					(size 2.54 2.54)
				)
			)
		)
	)
	(footprint ""
		(layer "F.Cu")
		(at 52.07 -125.73)
		(property "Reference" "SP55"
			(at 0 0 0)
			(layer "F.SilkS")
			(hide yes)
			(effects
				(font
					(size 1.27 1.27)
				)
			)
		)
		(property "Value" ""
			(at 0 0 0)
			(layer "F.Fab")
			(effects
				(font
					(size 1.27 1.27)
				)
			)
		)
		(duplicate_pad_numbers_are_jumpers no)
	)
	(footprint ""
		(layer "F.Cu")
		(at 57.785 -130.556)
		(property "Reference" "SP28"
			(at 0 0 0)
			(layer "F.SilkS")
			(hide yes)
			(effects
				(font
					(size 1.27 1.27)
				)
			)
		)
		(property "Value" ""
			(at 0 0 0)
			(layer "F.Fab")
			(effects
				(font
					(size 1.27 1.27)
				)
			)
		)
		(duplicate_pad_numbers_are_jumpers no)
	)
)
